(kicad_pcb
	(version 20240108)
	(generator "pcbnew")
	(generator_version "8.0")
	(general
		(thickness 1.62)
		(legacy_teardrops no)
	)
	(paper "A4")
	(title_block
		(title "Jetson Orin Baseboard")
		(date "2025-03-12")
		(rev "1.3.4")
		(company "Antmicro Ltd")
		(comment 1 "www.antmicro.com")
		(comment 9 "footprints 515-519 of 677")
	)
	(layers
		(0 "F.Cu" signal)
		(1 "In1.Cu" signal)
		(2 "In2.Cu" signal)
		(3 "In3.Cu" signal)
		(4 "In4.Cu" jumper)
		(5 "In5.Cu" signal)
		(6 "In6.Cu" signal)
		(31 "B.Cu" signal)
		(32 "B.Adhes" user "B.Adhesive")
		(33 "F.Adhes" user "F.Adhesive")
		(34 "B.Paste" user)
		(35 "F.Paste" user)
		(36 "B.SilkS" user "B.Silkscreen")
		(37 "F.SilkS" user "F.Silkscreen")
		(38 "B.Mask" user)
		(39 "F.Mask" user)
		(40 "Dwgs.User" user "User.Drawings")
		(41 "Cmts.User" user "User.Comments")
		(42 "Eco1.User" user "User.Eco1")
		(43 "Eco2.User" user "User.Eco2")
		(44 "Edge.Cuts" user)
		(45 "Margin" user)
		(46 "B.CrtYd" user "B.Courtyard")
		(47 "F.CrtYd" user "F.Courtyard")
		(48 "B.Fab" user)
		(49 "F.Fab" user)
	)
	(footprint "antmicro-footprints:R_0402_1005Metric"
		(layer "B.Cu")
		(at 57.55 110.45 180)
		(descr "Resistor SMD 0402")
		(tags "resistor SMD 0402")
		(property "Reference" "R58"
			(at -2.97 -0.3 0)
			(layer "B.SilkS")
			(effects
				(font
					(size 0.7 0.7)
					(thickness 0.15)
				)
				(justify left bottom mirror)
			)
		)
		(property "Value" "R_0R_0402"
			(at 0 -1.4 0)
			(layer "B.Fab")
			(effects
				(font
					(size 0.7 0.7)
					(thickness 0.15)
				)
				(justify left bottom mirror)
			)
		)
		(property "Footprint" "antmicro-footprints:R_0402_1005Metric"
			(at 0 0 180)
			(layer "F.Fab")
			(hide yes)
			(effects
				(font
					(size 1.27 1.27)
					(thickness 0.15)
				)
			)
		)
		(property "Datasheet" "https://industrial.panasonic.com/cdbs/www-data/pdf/RDA0000/AOA0000C301.pdf"
			(at 0 0 180)
			(layer "F.Fab")
			(hide yes)
			(effects
				(font
					(size 1.27 1.27)
					(thickness 0.15)
				)
			)
		)
		(property "Author" "Antmicro"
			(at 115.1 220.9 0)
			(layer "B.Fab")
			(hide yes)
			(effects
				(font
					(size 1 1)
					(thickness 0.15)
				)
				(justify mirror)
			)
		)
		(property "Current" "1A"
			(at 115.1 220.9 0)
			(layer "B.Fab")
			(hide yes)
			(effects
				(font
					(size 1 1)
					(thickness 0.15)
				)
				(justify mirror)
			)
		)
		(property "License" "Apache-2.0"
			(at 115.1 220.9 0)
			(layer "B.Fab")
			(hide yes)
			(effects
				(font
					(size 1 1)
					(thickness 0.15)
				)
				(justify mirror)
			)
		)
		(property "MPN" "ERJ2GE0R00X"
			(at 115.1 220.9 0)
			(layer "B.Fab")
			(hide yes)
			(effects
				(font
					(size 1 1)
					(thickness 0.15)
				)
				(justify mirror)
			)
		)
		(property "Manufacturer" "Panasonic"
			(at 115.1 220.9 0)
			(layer "B.Fab")
			(hide yes)
			(effects
				(font
					(size 1 1)
					(thickness 0.15)
				)
				(justify mirror)
			)
		)
		(property "Tolerance" ""
			(at 115.1 220.9 0)
			(layer "B.Fab")
			(hide yes)
			(effects
				(font
					(size 1 1)
					(thickness 0.15)
				)
				(justify mirror)
			)
		)
		(property "Val" "0R"
			(at 115.1 220.9 0)
			(layer "B.Fab")
			(hide yes)
			(effects
				(font
					(size 1 1)
					(thickness 0.15)
				)
				(justify mirror)
			)
		)
		(sheetname "USB Debug, DP")
		(sheetfile "usb.kicad_sch")
		(attr smd exclude_from_pos_files exclude_from_bom dnp)
		(fp_rect
			(start -0.925 0.47)
			(end 0.925 -0.47)
			(stroke
				(width 0.05)
				(type default)
			)
			(fill none)
			(layer "B.CrtYd")
		)
		(fp_rect
			(start -0.5 0.25)
			(end 0.5 -0.25)
			(stroke
				(width 0.15)
				(type solid)
			)
			(fill none)
			(layer "B.Fab")
		)
		(fp_text user "${REFERENCE}"
			(at -0.95 -3.168 0)
			(layer "B.Fab")
			(hide yes)
			(effects
				(font
					(size 0.7 0.7)
					(thickness 0.15)
				)
				(justify left bottom mirror)
			)
		)
		(fp_text user "Author: Antmicro"
			(at -0.95 -4.169 0)
			(layer "B.Fab")
			(hide yes)
			(effects
				(font
					(size 0.7 0.7)
					(thickness 0.15)
				)
				(justify left bottom mirror)
			)
		)
		(fp_text user "License: Apache-2.0"
			(at -0.95 -5.169 0)
			(layer "B.Fab")
			(hide yes)
			(effects
				(font
					(size 0.7 0.7)
					(thickness 0.15)
				)
				(justify left bottom mirror)
			)
		)
		(pad "1" smd roundrect
			(at -0.48 0 180)
			(size 0.59 0.64)
			(layers "B.Cu" "B.Paste" "B.Mask")
			(roundrect_rratio 0.25)
			(net 279 "PWR_SOFT")
			(pintype "passive")
		)
		(pad "2" smd roundrect
			(at 0.48 0 180)
			(size 0.59 0.64)
			(layers "B.Cu" "B.Paste" "B.Mask")
			(roundrect_rratio 0.25)
			(net 648 "Net-(U5-~{RTS})")
			(pintype "passive")
		)
	)
	(footprint "antmicro-footprints:SOT-523"
		(layer "B.Cu")
		(at 59.36 88.9)
		(property "Reference" "Q5"
			(at -2.68 1 0)
			(layer "B.SilkS")
			(effects
				(font
					(size 0.7 0.7)
					(thickness 0.15)
				)
				(justify right bottom mirror)
			)
		)
		(property "Value" "PJE138K"
			(at 0.1 -1.824 0)
			(layer "B.Fab")
			(effects
				(font
					(size 0.7 0.7)
					(thickness 0.15)
				)
				(justify right bottom mirror)
			)
		)
		(property "Footprint" "antmicro-footprints:SOT-523"
			(at 0 0 0)
			(layer "F.Fab")
			(hide yes)
			(effects
				(font
					(size 1.27 1.27)
					(thickness 0.15)
				)
			)
		)
		(property "Datasheet" "https://www.mouser.com/datasheet/2/1057/PJE138K-1876698.pdf"
			(at 0 0 0)
			(layer "F.Fab")
			(hide yes)
			(effects
				(font
					(size 1.27 1.27)
					(thickness 0.15)
				)
			)
		)
		(property "Author" "Antmicro"
			(at 0 0 0)
			(layer "B.Fab")
			(hide yes)
			(effects
				(font
					(size 1 1)
					(thickness 0.15)
				)
				(justify mirror)
			)
		)
		(property "License" "Apache-2.0"
			(at 0 0 0)
			(layer "B.Fab")
			(hide yes)
			(effects
				(font
					(size 1 1)
					(thickness 0.15)
				)
				(justify mirror)
			)
		)
		(property "MPN" "PJE138K_R1_00001"
			(at 0 0 0)
			(layer "B.Fab")
			(hide yes)
			(effects
				(font
					(size 1 1)
					(thickness 0.15)
				)
				(justify mirror)
			)
		)
		(property "Manufacturer" "PANJIT"
			(at 0 0 0)
			(layer "B.Fab")
			(hide yes)
			(effects
				(font
					(size 1 1)
					(thickness 0.15)
				)
				(justify mirror)
			)
		)
		(sheetname "Supply")
		(sheetfile "supply.kicad_sch")
		(attr smd)
		(fp_line
			(start -0.927 0.351)
			(end -0.927 0.051)
			(stroke
				(width 0.15)
				(type solid)
			)
			(layer "B.SilkS")
		)
		(fp_line
			(start -0.725 0.551)
			(end -0.927 0.351)
			(stroke
				(width 0.15)
				(type solid)
			)
			(layer "B.SilkS")
		)
		(fp_line
			(start -0.277 0.551)
			(end -0.725 0.551)
			(stroke
				(width 0.15)
				(type solid)
			)
			(layer "B.SilkS")
		)
		(fp_line
			(start -0.277 0.75)
			(end -0.277 0.551)
			(stroke
				(width 0.15)
				(type solid)
			)
			(layer "B.SilkS")
		)
		(fp_circle
			(center -0.9652 -0.9652)
			(end -0.9152 -0.9652)
			(stroke
				(width 0.15)
				(type solid)
			)
			(fill solid)
			(layer "B.SilkS")
		)
		(fp_line
			(start -1.12 -1.15)
			(end -1.12 1.16)
			(stroke
				(width 0.05)
				(type solid)
			)
			(layer "B.CrtYd")
		)
		(fp_line
			(start 1.1 -1.15)
			(end -1.12 -1.15)
			(stroke
				(width 0.05)
				(type solid)
			)
			(layer "B.CrtYd")
		)
		(fp_line
			(start 1.1 -1.15)
			(end 1.1 1.16)
			(stroke
				(width 0.05)
				(type solid)
			)
			(layer "B.CrtYd")
		)
		(fp_line
			(start 1.1 1.16)
			(end -1.12 1.16)
			(stroke
				(width 0.05)
				(type solid)
			)
			(layer "B.CrtYd")
		)
		(fp_line
			(start -0.802 -0.424)
			(end -0.802 0.276)
			(stroke
				(width 0.15)
				(type solid)
			)
			(layer "B.Fab")
		)
		(fp_line
			(start -0.802 -0.424)
			(end 0.8 -0.424)
			(stroke
				(width 0.15)
				(type solid)
			)
			(layer "B.Fab")
		)
		(fp_line
			(start -0.802 0.276)
			(end -0.652 0.425)
			(stroke
				(width 0.15)
				(type solid)
			)
			(layer "B.Fab")
		)
		(fp_line
			(start -0.652 0.425)
			(end 0.8 0.425)
			(stroke
				(width 0.15)
				(type solid)
			)
			(layer "B.Fab")
		)
		(fp_line
			(start 0.8 -0.424)
			(end 0.8 0.425)
			(stroke
				(width 0.15)
				(type solid)
			)
			(layer "B.Fab")
		)
		(fp_circle
			(center -0.9652 -0.9652)
			(end -0.9144 -0.9652)
			(stroke
				(width 0.15)
				(type solid)
			)
			(fill none)
			(layer "B.Fab")
		)
		(fp_text user "License: Apache-2.0"
			(at -1.12 -5.024 0)
			(layer "B.Fab")
			(hide yes)
			(effects
				(font
					(size 0.7 0.7)
					(thickness 0.15)
				)
				(justify right bottom mirror)
			)
		)
		(fp_text user "Author: Antmicro"
			(at -1.12 -6.224 0)
			(layer "B.Fab")
			(hide yes)
			(effects
				(font
					(size 0.7 0.7)
					(thickness 0.15)
				)
				(justify right bottom mirror)
			)
		)
		(fp_text user "${REFERENCE}"
			(at -1.12 -3.824 0)
			(layer "B.Fab")
			(hide yes)
			(effects
				(font
					(size 0.7 0.7)
					(thickness 0.15)
				)
				(justify right bottom mirror)
			)
		)
		(pad "1" smd rect
			(at -0.5 -0.65)
			(size 0.4 0.51)
			(layers "B.Cu" "B.Paste" "B.Mask")
			(net 86 "~{RESET}")
			(pinfunction "G")
			(pintype "passive")
		)
		(pad "2" smd rect
			(at 0.498 -0.65)
			(size 0.4 0.51)
			(layers "B.Cu" "B.Paste" "B.Mask")
			(net 1 "GND")
			(pinfunction "S")
			(pintype "passive")
		)
		(pad "3" smd rect
			(at 0 0.652)
			(size 0.4 0.51)
			(layers "B.Cu" "B.Paste" "B.Mask")
			(net 768 "/Supply/5V_GATE")
			(pinfunction "D")
			(pintype "passive")
		)
	)
	(footprint "antmicro-footprints:TP_SMD_0.75mm"
		(layer "B.Cu")
		(at 59.21 104.12 -135)
		(property "Reference" "TP24"
			(at 0 0.6 45)
			(layer "B.SilkS")
			(hide yes)
			(effects
				(font
					(size 0.7 0.7)
					(thickness 0.15)
				)
				(justify left bottom mirror)
			)
		)
		(property "Value" "TP_0.75mm_SMD"
			(at 0 -1.2 45)
			(layer "B.Fab")
			(effects
				(font
					(size 0.7 0.7)
					(thickness 0.15)
				)
				(justify left bottom mirror)
			)
		)
		(property "Footprint" "antmicro-footprints:TP_SMD_0.75mm"
			(at 0 0 -135)
			(layer "F.Fab")
			(hide yes)
			(effects
				(font
					(size 1.27 1.27)
					(thickness 0.15)
				)
			)
		)
		(property "Author" "Antmicro"
			(at 27.453834 219.611751 0)
			(layer "B.Fab")
			(hide yes)
			(effects
				(font
					(size 1 1)
					(thickness 0.15)
				)
				(justify mirror)
			)
		)
		(property "License" "Apache-2.0"
			(at 27.453834 219.611751 0)
			(layer "B.Fab")
			(hide yes)
			(effects
				(font
					(size 1 1)
					(thickness 0.15)
				)
				(justify mirror)
			)
		)
		(property "MPN" ""
			(at 27.453834 219.611751 0)
			(layer "B.Fab")
			(hide yes)
			(effects
				(font
					(size 1 1)
					(thickness 0.15)
				)
				(justify mirror)
			)
		)
		(property "Manufacturer" ""
			(at 27.453834 219.611751 0)
			(layer "B.Fab")
			(hide yes)
			(effects
				(font
					(size 1 1)
					(thickness 0.15)
				)
				(justify mirror)
			)
		)
		(sheetname "USB Debug, DP")
		(sheetfile "usb.kicad_sch")
		(attr exclude_from_pos_files exclude_from_bom)
		(fp_circle
			(center 0 0)
			(end 0.475 0)
			(stroke
				(width 0.05)
				(type default)
			)
			(fill none)
			(layer "B.CrtYd")
		)
		(fp_text user "License: Apache-2.0"
			(at -0.4 -5.101 45)
			(layer "B.Fab")
			(hide yes)
			(effects
				(font
					(size 0.7 0.7)
					(thickness 0.15)
				)
				(justify left bottom mirror)
			)
		)
		(fp_text user "${REFERENCE}"
			(at -0.4 -2.7 45)
			(layer "B.Fab")
			(hide yes)
			(effects
				(font
					(size 0.7 0.7)
					(thickness 0.15)
				)
				(justify left bottom mirror)
			)
		)
		(fp_text user "Author: Antmicro"
			(at -0.4 -3.901 45)
			(layer "B.Fab")
			(hide yes)
			(effects
				(font
					(size 0.7 0.7)
					(thickness 0.15)
				)
				(justify left bottom mirror)
			)
		)
		(pad "1" smd circle
			(at 0 0 225)
			(size 0.75 0.75)
			(layers "B.Cu" "B.Mask")
			(net 639 "/USB Debug, DP/PDC_I2C3_SCL")
			(pinfunction "1")
			(pintype "passive")
		)
	)
	(footprint "antmicro-footprints:R_0402_1005Metric"
		(layer "B.Cu")
		(at 138.8 123 180)
		(descr "Resistor SMD 0402")
		(tags "resistor SMD 0402")
		(property "Reference" "R190"
			(at -1.11 1.425 180)
			(layer "B.SilkS")
			(effects
				(font
					(size 0.7 0.7)
					(thickness 0.15)
				)
				(justify left bottom mirror)
			)
		)
		(property "Value" "R_15k_0402"
			(at 0 -1.4 0)
			(layer "B.Fab")
			(effects
				(font
					(size 0.7 0.7)
					(thickness 0.15)
				)
				(justify left bottom mirror)
			)
		)
		(property "Footprint" "antmicro-footprints:R_0402_1005Metric"
			(at 0 0 180)
			(layer "F.Fab")
			(hide yes)
			(effects
				(font
					(size 1.27 1.27)
					(thickness 0.15)
				)
			)
		)
		(property "Datasheet" "https://www.bourns.com/docs/product-datasheets/cr.pdf"
			(at 0 0 180)
			(layer "F.Fab")
			(hide yes)
			(effects
				(font
					(size 1.27 1.27)
					(thickness 0.15)
				)
			)
		)
		(property "Author" "Antmicro"
			(at 277.6 246 0)
			(layer "B.Fab")
			(hide yes)
			(effects
				(font
					(size 1 1)
					(thickness 0.15)
				)
				(justify mirror)
			)
		)
		(property "License" "Apache-2.0"
			(at 277.6 246 0)
			(layer "B.Fab")
			(hide yes)
			(effects
				(font
					(size 1 1)
					(thickness 0.15)
				)
				(justify mirror)
			)
		)
		(property "MPN" "CR0402-FX-1502GLF"
			(at 277.6 246 0)
			(layer "B.Fab")
			(hide yes)
			(effects
				(font
					(size 1 1)
					(thickness 0.15)
				)
				(justify mirror)
			)
		)
		(property "Manufacturer" "Bourns"
			(at 277.6 246 0)
			(layer "B.Fab")
			(hide yes)
			(effects
				(font
					(size 1 1)
					(thickness 0.15)
				)
				(justify mirror)
			)
		)
		(property "Tolerance" "1%"
			(at 277.6 246 0)
			(layer "B.Fab")
			(hide yes)
			(effects
				(font
					(size 1 1)
					(thickness 0.15)
				)
				(justify mirror)
			)
		)
		(property "Val" "15k"
			(at 277.6 246 0)
			(layer "B.Fab")
			(hide yes)
			(effects
				(font
					(size 1 1)
					(thickness 0.15)
				)
				(justify mirror)
			)
		)
		(sheetname "Peripherals")
		(sheetfile "peripherals.kicad_sch")
		(attr smd)
		(fp_rect
			(start -0.925 0.47)
			(end 0.925 -0.47)
			(stroke
				(width 0.05)
				(type default)
			)
			(fill none)
			(layer "B.CrtYd")
		)
		(fp_rect
			(start -0.5 0.25)
			(end 0.5 -0.25)
			(stroke
				(width 0.15)
				(type solid)
			)
			(fill none)
			(layer "B.Fab")
		)
		(fp_text user "License: Apache-2.0"
			(at -0.95 -5.169 0)
			(layer "B.Fab")
			(hide yes)
			(effects
				(font
					(size 0.7 0.7)
					(thickness 0.15)
				)
				(justify left bottom mirror)
			)
		)
		(fp_text user "Author: Antmicro"
			(at -0.95 -4.169 0)
			(layer "B.Fab")
			(hide yes)
			(effects
				(font
					(size 0.7 0.7)
					(thickness 0.15)
				)
				(justify left bottom mirror)
			)
		)
		(fp_text user "${REFERENCE}"
			(at -0.95 -3.168 0)
			(layer "B.Fab")
			(hide yes)
			(effects
				(font
					(size 0.7 0.7)
					(thickness 0.15)
				)
				(justify left bottom mirror)
			)
		)
		(pad "1" smd roundrect
			(at -0.48 0 180)
			(size 0.59 0.64)
			(layers "B.Cu" "B.Paste" "B.Mask")
			(roundrect_rratio 0.25)
			(net 1 "GND")
			(pintype "passive")
		)
		(pad "2" smd roundrect
			(at 0.48 0 180)
			(size 0.59 0.64)
			(layers "B.Cu" "B.Paste" "B.Mask")
			(roundrect_rratio 0.25)
			(net 685 "Net-(U35-ISET)")
			(pintype "passive")
		)
	)
	(footprint "antmicro-footprints:R_0402_1005Metric"
		(layer "B.Cu")
		(at 91.3 118 90)
		(descr "Resistor SMD 0402")
		(tags "resistor SMD 0402")
		(property "Reference" "R282"
			(at 1.65 4.8 -90)
			(layer "B.SilkS")
			(effects
				(font
					(size 0.7 0.7)
					(thickness 0.15)
				)
				(justify left bottom mirror)
			)
		)
		(property "Value" "R_2k2_0402"
			(at 0 -1.4 -90)
			(layer "B.Fab")
			(effects
				(font
					(size 0.7 0.7)
					(thickness 0.15)
				)
				(justify left bottom mirror)
			)
		)
		(property "Footprint" "antmicro-footprints:R_0402_1005Metric"
			(at 0 0 90)
			(layer "F.Fab")
			(hide yes)
			(effects
				(font
					(size 1.27 1.27)
					(thickness 0.15)
				)
			)
		)
		(property "Datasheet" "https://www.bourns.com/docs/product-datasheets/cr.pdf"
			(at 0 0 90)
			(layer "F.Fab")
			(hide yes)
			(effects
				(font
					(size 1.27 1.27)
					(thickness 0.15)
				)
			)
		)
		(property "Author" "Antmicro"
			(at 209.3 26.7 0)
			(layer "B.Fab")
			(hide yes)
			(effects
				(font
					(size 1 1)
					(thickness 0.15)
				)
				(justify mirror)
			)
		)
		(property "License" "Apache-2.0"
			(at 209.3 26.7 0)
			(layer "B.Fab")
			(hide yes)
			(effects
				(font
					(size 1 1)
					(thickness 0.15)
				)
				(justify mirror)
			)
		)
		(property "MPN" "CR0402-FX-2201GLF"
			(at 209.3 26.7 0)
			(layer "B.Fab")
			(hide yes)
			(effects
				(font
					(size 1 1)
					(thickness 0.15)
				)
				(justify mirror)
			)
		)
		(property "Manufacturer" "Bourns"
			(at 209.3 26.7 0)
			(layer "B.Fab")
			(hide yes)
			(effects
				(font
					(size 1 1)
					(thickness 0.15)
				)
				(justify mirror)
			)
		)
		(property "Tolerance" "1%"
			(at 209.3 26.7 0)
			(layer "B.Fab")
			(hide yes)
			(effects
				(font
					(size 1 1)
					(thickness 0.15)
				)
				(justify mirror)
			)
		)
		(property "Val" "2k2"
			(at 209.3 26.7 0)
			(layer "B.Fab")
			(hide yes)
			(effects
				(font
					(size 1 1)
					(thickness 0.15)
				)
				(justify mirror)
			)
		)
		(sheetname "HDMI")
		(sheetfile "hdmi.kicad_sch")
		(attr smd exclude_from_pos_files exclude_from_bom dnp)
		(fp_rect
			(start -0.925 0.47)
			(end 0.925 -0.47)
			(stroke
				(width 0.05)
				(type default)
			)
			(fill none)
			(layer "B.CrtYd")
		)
		(fp_rect
			(start -0.5 0.25)
			(end 0.5 -0.25)
			(stroke
				(width 0.15)
				(type solid)
			)
			(fill none)
			(layer "B.Fab")
		)
		(fp_text user "License: Apache-2.0"
			(at -0.95 -5.169 -90)
			(layer "B.Fab")
			(hide yes)
			(effects
				(font
					(size 0.7 0.7)
					(thickness 0.15)
				)
				(justify left bottom mirror)
			)
		)
		(fp_text user "${REFERENCE}"
			(at -0.95 -3.168 -90)
			(layer "B.Fab")
			(hide yes)
			(effects
				(font
					(size 0.7 0.7)
					(thickness 0.15)
				)
				(justify left bottom mirror)
			)
		)
		(fp_text user "Author: Antmicro"
			(at -0.95 -4.169 -90)
			(layer "B.Fab")
			(hide yes)
			(effects
				(font
					(size 0.7 0.7)
					(thickness 0.15)
				)
				(justify left bottom mirror)
			)
		)
		(pad "1" smd roundrect
			(at -0.48 0 90)
			(size 0.59 0.64)
			(layers "B.Cu" "B.Paste" "B.Mask")
			(roundrect_rratio 0.25)
			(net 519 "/HDMI/HDMI_SCL_5V")
			(pintype "passive")
		)
		(pad "2" smd roundrect
			(at 0.48 0 90)
			(size 0.59 0.64)
			(layers "B.Cu" "B.Paste" "B.Mask")
			(roundrect_rratio 0.25)
			(net 498 "/HDMI/5V_HDMI")
			(pintype "passive")
		)
	)
)
